FILE_TYPE = CONNECTIVITY;
{Allegro Design Entry HDL 16.6-p007 (v16-6-112F) 10/10/2012}
"PAGE_NUMBER" = 168;
0"NC";
1"FM_SOL_UART_CH_SEL";
2"GND\g";
3"FM_UART_SEL_N";
4"GND\g";
5"P3V3_STBY\g";
6"GND\g";
7"P3V3_STBY\g";
8"GND\g";
9"P5V_STBY\g";
10"P3V3_STBY\g";
11"UART_SELECT_Q";
12"FM_UART_SWITCH_N";
13"FM_DB_UART_SEL2_N";
14"FM_DB_UART_SEL1_N";
15"FM_DB_UART_SEL4_N";
16"FM_DB_PRESENT";
17"FM_DB_UART_SEL3_N";
18"FM_DB_UART_SEL0_N";
19"FM_POST_CARD_PRES_BMC_N";
20"TP_FET_Q56_4";
21"TP_FET_Q56_3";
%"RES"
"2","(-4225,3050)","0","mstr_discrete","I11";
;
CDS_SEC"1"
ROOM"UART_MUX"
CDS_LOCATION"R1L36"
SEC"1"
BOM_COST"DEBUG"
CDS_LIB"mstr_discrete"
SEC_TYPE"0402"
WATTAGE"1/16W"
MATERIAL"CHIP"
PACK_TYPE"0402"
TOLERANCE"1%"
VALUE"1.00K"
PART_NUMBER"G21796-026"
LOCATION"R1L36";
"A"
$PN"1"7;
"B"
$PN"2"16;
%"GND"
"1","(-4225,2525)","0","mstr_symbols","I14";
;
HDL_POWER"GND"
BODY_TYPE"PLUMBING"
CDS_LIB"mstr_symbols"
SIZE"1B"
VOLTAGE"0.0V";
"A\NAC"4;
%"FET_N_DUAL"
"5","(-1525,4425)","0","mstr_discrete","I18";
;
CDS_SEC"2"
PACK_TYPE"SMLF"
BOM_COST"DEBUG"
CDS_LIB"mstr_discrete"
SEC_TYPE"SMLF"
SEC"2"
CDS_LOCATION"Q1L4"
ROOM"UART_MUX"
LOCATION"Q1L4"
PART_NUMBER"D24280-001"
VALUE"2N7002DW"
MATERIAL"FET";
"GATE <SIZE -1..0>"
$PN"5"20;
"SOURCE <SIZE-1..0>"
$PN"4"20;
"DRAIN <SIZE -1..0>"
$PN"3"21;
%"FET_N_DUAL"
"5","(-3250,3000)","0","mstr_discrete","I19";
;
CDS_SEC"1"
ROOM"UART_MUX"
CDS_LOCATION"Q1L4"
SEC"1"
SEC_TYPE"SMLF"
CDS_LIB"mstr_discrete"
BOM_COST"DEBUG"
PACK_TYPE"SMLF"
MATERIAL"FET"
VALUE"2N7002DW"
PART_NUMBER"D24280-001"
LOCATION"Q1L4";
"GATE <SIZE -1..0>"
$PN"2"16;
"SOURCE <SIZE-1..0>"
$PN"1"6;
"DRAIN <SIZE -1..0>"
$PN"6"19;
%"DIODE"
"1","(-6400,2750)","0","mstr_discrete","I2";
;
CDS_SEC"1"
ROOM"UART_MUX"
CDS_LOCATION"CR1L1"
SEC"1"
BOM_COST"DEBUG"
CDS_LIB"mstr_discrete"
SEC_TYPE"SM"
MATERIAL"IC"
PACK_TYPE"SM"
PART_NUMBER"D89194-001"
LOCATION"CR1L1"
VALUE"1N4148W";
"C"
$PN"1"14;
"A"
$PN"2"18;
%"RES"
"2","(-3250,3425)","0","mstr_discrete","I22";
;
CDS_SEC"1"
ROOM"UART_MUX"
CDS_LOCATION"R1L38"
SEC"1"
BOM_COST"DEBUG"
CDS_LIB"mstr_discrete"
SEC_TYPE"0402"
WATTAGE"1/16W"
MATERIAL"CHIP"
PACK_TYPE"0402"
TOLERANCE"1%"
VALUE"1.00K"
PART_NUMBER"G21796-026"
LOCATION"R1L38";
"A"
$PN"1"5;
"B"
$PN"2"19;
%"P3V3_STBY"
"1","(-3250,3625)","0","mstr_symbols","I24";
;
HDL_POWER"P3V3_STBY"
BODY_TYPE"PLUMBING"
SIZE"1B"
CDS_LIB"mstr_symbols"
VOLTAGE"3.3V";
"G\NAC"5;
%"GND"
"1","(-3250,2675)","0","mstr_symbols","I26";
;
HDL_POWER"GND"
BODY_TYPE"PLUMBING"
SIZE"1B"
CDS_LIB"mstr_symbols"
VOLTAGE"0.0V";
"A\NAC"6;
%"P3V3_STBY"
"1","(-4225,3250)","0","mstr_symbols","I29";
;
HDL_POWER"P3V3_STBY"
BODY_TYPE"PLUMBING"
SIZE"1B"
CDS_LIB"mstr_symbols"
VOLTAGE"3.3V";
"G\NAC"7;
%"DIODE"
"1","(-5850,2750)","0","mstr_discrete","I3";
;
CDS_SEC"1"
ROOM"UART_MUX"
CDS_LOCATION"CR1L2"
SEC"1"
BOM_COST"DEBUG"
CDS_LIB"mstr_discrete"
SEC_TYPE"SM"
MATERIAL"IC"
LOCATION"CR1L2"
VALUE"1N4148W"
PACK_TYPE"SM"
PART_NUMBER"D89194-001";
"C"
$PN"1"13;
"A"
$PN"2"14;
%"GND"
"1","(-5250,1575)","0","mstr_symbols","I32";
;
CDS_LIB"mstr_symbols"
HDL_POWER"GND"
SIZE"1B"
BODY_TYPE"PLUMBING"
VOLTAGE"0.0V";
"A\NAC"8;
%"RES"
"2","(-5250,1825)","0","mstr_discrete","I33";
;
CDS_SEC"1"
$SEC"1"
CDS_LOCATION"R6W14"
BOM_COST"SM_HM"
ROOM"BMC_VOLT_MONITOR"
CDS_LIB"mstr_discrete"
PART_NUMBER"G21796-140"
PACK_TYPE"0402"
MATERIAL"CHIP"
TOLERANCE"1%"
VALUE"5.11K"
LOCATION"R6W14"
WATTAGE"1/16W";
"A"
$PN"1"11;
"B"
$PN"2"8;
%"RES"
"2","(-5250,2175)","0","mstr_discrete","I34";
;
CDS_SEC"1"
$SEC"1"
CDS_LOCATION"R6W13"
ROOM"PVCCIN_CPU1_VR"
CDS_LIB"mstr_discrete"
LOCATION"R6W13"
VALUE"15.0K"
TOLERANCE"1%"
PACK_TYPE"0402"
PART_NUMBER"G21796-107"
MATERIAL"CHIP"
WATTAGE"1/16W";
"A"
$PN"1"9;
"B"
$PN"2"11;
%"P5V_STBY"
"1","(-5250,2350)","0","mstr_symbols","I35";
;
VOLTAGE"5.0V"
SIZE"1B"
HDL_POWER"P5V_STBY"
BODY_TYPE"PLUMBING"
CDS_LIB"mstr_symbols";
"G\NAC"9;
%"GND"
"1","(-3950,975)","0","mstr_symbols","I36";
;
HDL_POWER"GND"
BODY_TYPE"PLUMBING"
SIZE"1B"
CDS_LIB"mstr_symbols"
VOLTAGE"0.0V";
"A\NAC"2;
%"NPN"
"1","(-5975,1500)","5","mstr_discrete","I37";
;
CDS_LOCATION"Q6W3"
ROOM"UART_MUX"
SEC"1"
BOM_COST"DEBUG"
CDS_LIB"mstr_discrete"
SEC_TYPE"SM"
CDS_SEC"1"
PACK_TYPE"SM"
VALUE"MMBT3904"
PART_NUMBER"C52245-001"
MATERIAL"IC"
LOCATION"Q6W3";
"C"
$PN"3"3;
"E"
$PN"2"12;
"B"
$PN"1"11;
%"P3V3_STBY"
"1","(-3950,2375)","0","mstr_symbols","I38";
;
HDL_POWER"P3V3_STBY"
BODY_TYPE"PLUMBING"
SIZE"1B"
CDS_LIB"mstr_symbols"
VOLTAGE"3.3V";
"G\NAC"10;
%"RES"
"2","(-3950,2000)","0","mstr_discrete","I39";
;
CDS_SEC"1"
$SEC"1"
CDS_LOCATION"R6W16"
CDS_LIB"mstr_discrete"
ROOM"HOT_SWAP"
PACK_TYPE"0402"
MATERIAL"CHIP"
WATTAGE"1/16W"
VALUE"10.0K"
LOCATION"R6W16"
TOLERANCE"1%"
PART_NUMBER"G21796-016";
"A"
$PN"1"10;
"B"
$PN"2"1;
%"DIODE"
"1","(-5375,2750)","0","mstr_discrete","I4";
;
CDS_SEC"1"
ROOM"UART_MUX"
CDS_LOCATION"CR1L3"
SEC"1"
BOM_COST"DEBUG"
CDS_LIB"mstr_discrete"
SEC_TYPE"SM"
MATERIAL"IC"
PACK_TYPE"SM"
LOCATION"CR1L3"
VALUE"1N4148W"
PART_NUMBER"D89194-001";
"C"
$PN"1"17;
"A"
$PN"2"13;
%"RES"
"2","(-4500,2000)","0","mstr_discrete","I40";
;
CDS_SEC"1"
$SEC"1"
CDS_LOCATION"R6W15"
ROOM"HOT_SWAP"
CDS_LIB"mstr_discrete"
LOCATION"R6W15"
WATTAGE"1/16W"
PART_NUMBER"G21796-016"
PACK_TYPE"0402"
MATERIAL"CHIP"
TOLERANCE"1%"
VALUE"10.0K";
"A"
$PN"1"10;
"B"
$PN"2"3;
%"FET_N"
"8","(-3950,1550)","0","mstr_discrete","I41";
;
PACK_TYPE"SOT23"
ROOM"V_SUPER"
MATERIAL"FET"
VALUE"2N7002"
PART_NUMBER"C79254-001"
CDS_LIB"mstr_discrete"
LOCATION"Q6W2";
"GATE"
$PN"?"3;
"DRN"
$PN"?"1;
"SRC"
$PN"?"2;
%"DIODE"
"1","(-4875,2750)","0","mstr_discrete","I5";
;
CDS_SEC"1"
ROOM"UART_MUX"
CDS_LOCATION"CR1L4"
SEC"1"
BOM_COST"DEBUG"
CDS_LIB"mstr_discrete"
SEC_TYPE"SM"
VALUE"1N4148W"
MATERIAL"IC"
PACK_TYPE"SM"
LOCATION"CR1L4"
PART_NUMBER"D89194-001";
"C"
$PN"1"15;
"A"
$PN"2"17;
%"RES"
"1","(-6975,2750)","0","mstr_discrete","I6";
;
CDS_SEC"1"
ROOM"UART_MUX"
CDS_LOCATION"R1L6"
SEC"1"
BOM_COST"DEBUG"
CDS_LIB"mstr_discrete"
SEC_TYPE"0402"
WATTAGE"1/16W"
MATERIAL"CHIP"
TOLERANCE"5%"
VALUE"0.0"
PACK_TYPE"0402"
PART_NUMBER"G21497-005"
LOCATION"R1L6";
"B"
$PN"2"18;
"A"
$PN"1"12;
%"NPN"
"1","(-4275,2750)","0","mstr_discrete","I8";
;
CDS_SEC"1"
ROOM"UART_MUX"
CDS_LOCATION"Q1L3"
SEC"1"
BOM_COST"DEBUG"
CDS_LIB"mstr_discrete"
SEC_TYPE"SM"
MATERIAL"IC"
LOCATION"Q1L3"
PACK_TYPE"SM"
VALUE"MMBT3904"
PART_NUMBER"C52245-001";
"C"
$PN"3"16;
"E"
$PN"2"4;
"B"
$PN"1"15;
END.
